(kicad_pcb
	(version 20260206)
	(generator "pcbnew")
	(generator_version "10.0")
	(general
		(thickness 1.6)
		(legacy_teardrops no)
	)
	(paper "A4")
	(title_block
		(title "Wiwynn_Tioga_Pass_MB.brd")
		(comment 1 "Tioga Pass / footprints 3189-3194 of 4770")
	)
	(layers
		(0 "F.Cu" signal "TOP")
		(4 "In1.Cu" signal "L2GND")
		(6 "In2.Cu" signal "L3")
		(8 "In3.Cu" signal "L4GND")
		(10 "In4.Cu" signal "L5")
		(12 "In5.Cu" signal "L6GND")
		(14 "In6.Cu" signal "L7VCC")
		(16 "In7.Cu" signal "L8VCC")
		(18 "In8.Cu" signal "L9GND")
		(20 "In9.Cu" signal "L10")
		(22 "In10.Cu" signal "L11GND")
		(24 "In11.Cu" signal "L12")
		(26 "In12.Cu" signal "L13GND")
		(2 "B.Cu" signal "BOTTOM")
		(9 "F.Adhes" user "F.Adhesive")
		(11 "B.Adhes" user "B.Adhesive")
		(13 "F.Paste" user "Package Geometry/Pastemask Top")
		(15 "B.Paste" user "Package Geometry/Pastemask Bottom")
		(5 "F.SilkS" user "Ref Des/Silkscreen Top")
		(7 "B.SilkS" user "Ref Des/Silkscreen Bottom")
		(1 "F.Mask" user "Board Geometry/Soldermask Top")
		(3 "B.Mask" user "Board Geometry/Soldermask Bottom")
		(17 "Dwgs.User" user "User.Drawings")
		(19 "Cmts.User" user "User.Comments")
		(21 "Eco1.User" user "User.Eco1")
		(23 "Eco2.User" user "User.Eco2")
		(25 "Edge.Cuts" user "Board Geometry/Outline")
		(27 "Margin" user)
		(31 "F.CrtYd" user "Package Geometry/Place Bound Top")
		(29 "B.CrtYd" user "Package Geometry/Place Bound Bottom")
		(35 "F.Fab" user "Ref Des/Assembly Top")
		(33 "B.Fab" user "Ref Des/Assembly Bottom")
	)
	(footprint ""
		(layer "B.Cu")
		(at 420.3065 -79.9465)
		(property "Reference" "Q2P1"
			(at -1.27508 3.76555 180)
			(unlocked yes)
			(layer "B.SilkS")
			(effects
				(font
					(size 0.7874 0.5842)
					(thickness 0.1524)
				)
				(justify left mirror)
			)
		)
		(property "Value" ""
			(at 0 0 0)
			(layer "B.Fab")
			(effects
				(font
					(size 1.27 1.27)
				)
				(justify mirror)
			)
		)
		(duplicate_pad_numbers_are_jumpers no)
		(fp_line
			(start -1.778 -0.5715)
			(end -1.778 0.3175)
			(stroke
				(width 0.1524)
				(type default)
			)
			(layer "B.SilkS")
		)
		(fp_line
			(start -1.778 2.4765)
			(end -1.778 1.5875)
			(stroke
				(width 0.1524)
				(type default)
			)
			(layer "B.SilkS")
		)
		(fp_line
			(start -0.9525 -0.5715)
			(end -1.778 -0.5715)
			(stroke
				(width 0.1524)
				(type default)
			)
			(layer "B.SilkS")
		)
		(fp_line
			(start -0.9525 2.4765)
			(end -1.778 2.4765)
			(stroke
				(width 0.1524)
				(type default)
			)
			(layer "B.SilkS")
		)
		(fp_line
			(start -0.381 0.635)
			(end -0.381 1.27)
			(stroke
				(width 0.1524)
				(type default)
			)
			(layer "B.SilkS")
		)
		(fp_circle
			(center 0.52197 -0.800608)
			(end 0.64897 -0.800608)
			(stroke
				(width 0.254)
				(type default)
			)
			(fill no)
			(layer "B.SilkS")
		)
		(fp_poly
			(pts
				(xy -1.778 2.4765) (xy -0.381 2.4765) (xy -0.381 -0.5715) (xy -1.778 -0.5715)
			)
			(stroke
				(width 0)
				(type default)
			)
			(fill no)
			(layer "B.CrtYd")
		)
		(fp_line
			(start -1.778 -0.5715)
			(end -0.381 -0.5715)
			(stroke
				(width 0.1)
				(type default)
			)
			(layer "B.Fab")
		)
		(fp_line
			(start -1.778 2.4765)
			(end -1.778 -0.5715)
			(stroke
				(width 0.1)
				(type default)
			)
			(layer "B.Fab")
		)
		(fp_line
			(start -0.381 -0.5715)
			(end -0.381 2.4765)
			(stroke
				(width 0.1)
				(type default)
			)
			(layer "B.Fab")
		)
		(fp_line
			(start -0.381 2.4765)
			(end -1.778 2.4765)
			(stroke
				(width 0.1)
				(type default)
			)
			(layer "B.Fab")
		)
		(fp_circle
			(center 0.9525 -0.9271)
			(end 1.0795 -0.9271)
			(stroke
				(width 0.254)
				(type default)
			)
			(fill no)
			(layer "B.Fab")
		)
		(pad "1" smd rect
			(at 0 0 180)
			(size 1.143 0.508)
			(layers "B.Cu" "B.Mask" "B.Paste")
			(net "FM_PMBUS_ALERT_BUF_EN_N")
		)
		(pad "2" smd rect
			(at 0 1.905 180)
			(size 1.143 0.508)
			(layers "B.Cu" "B.Mask" "B.Paste")
			(net "GND")
		)
		(pad "3" smd rect
			(at -2.159 0.9525 180)
			(size 1.143 0.508)
			(layers "B.Cu" "B.Mask" "B.Paste")
			(net "FM_PMBUS_ALERT_BUF_EN")
		)
	)
	(footprint ""
		(layer "B.Cu")
		(at 229.23881 -164.911786 90)
		(property "Reference" "T1D24"
			(at 0 0 90)
			(layer "B.SilkS")
			(hide yes)
			(effects
				(font
					(size 1.27 1.27)
				)
				(justify mirror)
			)
		)
		(property "Value" "*"
			(at 3.4036 -4.46405 90)
			(unlocked yes)
			(layer "B.Fab")
			(hide yes)
			(effects
				(font
					(size 0.889 0.889)
					(thickness 0.1524)
				)
				(justify mirror)
			)
		)
		(property "Device Type" "TEST-PAD-12P-1-GP-U_DISCRET-GBA"
			(at 3.4036 -5.98805 90)
			(unlocked yes)
			(layer "B.Fab")
			(hide yes)
			(effects
				(font
					(size 0.889 0.889)
					(thickness 0.1524)
				)
				(justify mirror)
			)
		)
		(duplicate_pad_numbers_are_jumpers no)
		(fp_line
			(start 2.3876 -4.826)
			(end -2.3622 -4.826)
			(stroke
				(width 0.1524)
				(type default)
			)
			(layer "B.SilkS")
		)
		(fp_line
			(start -2.3622 -4.826)
			(end -2.3622 3.4798)
			(stroke
				(width 0.1524)
				(type default)
			)
			(layer "B.SilkS")
		)
		(fp_line
			(start 2.3876 3.4798)
			(end 2.3876 -4.826)
			(stroke
				(width 0.1524)
				(type default)
			)
			(layer "B.SilkS")
		)
		(fp_line
			(start -2.3622 3.4798)
			(end 2.3876 3.4798)
			(stroke
				(width 0.1524)
				(type default)
			)
			(layer "B.SilkS")
		)
		(fp_rect
			(start 2.6416 3.7338)
			(end -2.6162 -5.08)
			(stroke
				(width 0)
				(type default)
			)
			(fill no)
			(layer "B.CrtYd")
		)
		(fp_rect
			(start 2.6416 3.7338)
			(end -2.6162 -5.08)
			(stroke
				(width 0)
				(type default)
			)
			(fill no)
			(layer "B.Fab")
		)
		(pad "1" smd circle
			(at -0.496824 -1.301496 270)
			(size 0.6604 0.6604)
			(layers "B.Cu" "B.Mask" "B.Paste")
			(net "L14_85OHM_10INCH_DN")
		)
		(pad "2" smd circle
			(at 0.503936 -1.301496 270)
			(size 0.6604 0.6604)
			(layers "B.Cu" "B.Mask" "B.Paste")
			(net "L14_85OHM_10INCH_DP")
		)
		(pad "3" smd custom
			(at 0.00889 0.370078 270)
			(size 0.74295 0.74295)
			(layers "B.Cu" "B.Mask" "B.Paste")
			(net "GND")
			(options
				(clearance outline)
				(anchor circle)
			)
			(primitives
				(gr_poly
					(pts
						(xy -2.1209 -1.4859) (xy 2.1209 -1.4859) (xy 2.1209 1.4859) (xy 1.08585 1.4859) (xy 1.08585 0.4699)
						(xy -1.08585 0.4699) (xy -1.08585 1.4859) (xy -2.1209 1.4859)
					)
					(width 0)
					(fill yes)
				)
			)
		)
		(pad "4" thru_hole circle
			(at -1.266444 -3.851656 270)
			(size 1.4478 1.4478)
			(drill 1.0414)
			(layers "*.Cu" "*.Mask")
			(remove_unused_layers no)
			(net "GND")
			(clearance 0.1524)
			(thermal_gap 0.1524)
		)
		(pad "5" thru_hole circle
			(at 1.273556 -3.851656 270)
			(size 1.4478 1.4478)
			(drill 1.0414)
			(layers "*.Cu" "*.Mask")
			(remove_unused_layers no)
			(net "GND")
			(clearance 0.1524)
			(thermal_gap 0.1524)
		)
		(pad "6" thru_hole circle
			(at -1.266444 2.498344 270)
			(size 1.4478 1.4478)
			(drill 1.0414)
			(layers "*.Cu" "*.Mask")
			(remove_unused_layers no)
			(net "GND")
			(clearance 0.1524)
			(thermal_gap 0.1524)
		)
		(pad "7" thru_hole circle
			(at 1.273556 2.498344 270)
			(size 1.4478 1.4478)
			(drill 1.0414)
			(layers "*.Cu" "*.Mask")
			(remove_unused_layers no)
			(net "GND")
			(clearance 0.1524)
			(thermal_gap 0.1524)
		)
		(pad "8" thru_hole circle
			(at -1.27 -0.4572 270)
			(size 0.7112 0.7112)
			(drill 0.4064)
			(layers "*.Cu" "*.Mask")
			(remove_unused_layers no)
			(net "GND")
			(clearance 0.1016)
			(thermal_gap 0.1016)
		)
		(pad "9" thru_hole circle
			(at -1.27 0.762 270)
			(size 0.7112 0.7112)
			(drill 0.4064)
			(layers "*.Cu" "*.Mask")
			(remove_unused_layers no)
			(net "GND")
			(clearance 0.1016)
			(thermal_gap 0.1016)
		)
		(pad "10" thru_hole circle
			(at 0.0254 0.762 270)
			(size 0.7112 0.7112)
			(drill 0.4064)
			(layers "*.Cu" "*.Mask")
			(remove_unused_layers no)
			(net "GND")
			(clearance 0.1016)
			(thermal_gap 0.1016)
		)
		(pad "11" thru_hole circle
			(at 1.27 0.762 270)
			(size 0.7112 0.7112)
			(drill 0.4064)
			(layers "*.Cu" "*.Mask")
			(remove_unused_layers no)
			(net "GND")
			(clearance 0.1016)
			(thermal_gap 0.1016)
		)
		(pad "12" thru_hole circle
			(at 1.27 -0.4572 270)
			(size 0.7112 0.7112)
			(drill 0.4064)
			(layers "*.Cu" "*.Mask")
			(remove_unused_layers no)
			(net "GND")
			(clearance 0.1016)
			(thermal_gap 0.1016)
		)
	)
	(footprint ""
		(layer "B.Cu")
		(at 393.446 -18.9103 180)
		(property "Reference" "R32W1"
			(at 0.8382 -0.67818 180)
			(unlocked yes)
			(layer "B.SilkS")
			(effects
				(font
					(size 0.4064 0.254)
					(thickness 0.1524)
				)
				(justify left mirror)
			)
		)
		(property "Value" ""
			(at 0 0 0)
			(layer "B.Fab")
			(effects
				(font
					(size 1.27 1.27)
				)
				(justify mirror)
			)
		)
		(duplicate_pad_numbers_are_jumpers no)
		(fp_poly
			(pts
				(xy 0.2794 -0.1016) (xy -0.2794 -0.1016) (xy -0.2794 0.9906) (xy 0.2794 0.9906)
			)
			(stroke
				(width 0)
				(type default)
			)
			(fill no)
			(layer "B.CrtYd")
		)
		(fp_line
			(start 0.2794 0.9906)
			(end -0.2794 0.9906)
			(stroke
				(width 0.1)
				(type default)
			)
			(layer "B.Fab")
		)
		(fp_line
			(start 0.2794 -0.1016)
			(end 0.2794 0.9906)
			(stroke
				(width 0.1)
				(type default)
			)
			(layer "B.Fab")
		)
		(fp_line
			(start -0.2794 0.9906)
			(end -0.2794 -0.1016)
			(stroke
				(width 0.1)
				(type default)
			)
			(layer "B.Fab")
		)
		(fp_line
			(start -0.2794 -0.1016)
			(end 0.2794 -0.1016)
			(stroke
				(width 0.1)
				(type default)
			)
			(layer "B.Fab")
		)
		(pad "1" smd rect
			(at 0 0)
			(size 0.508 0.508)
			(layers "B.Cu" "B.Mask" "B.Paste")
			(net "P3V3")
		)
		(pad "2" smd rect
			(at 0 0.889)
			(size 0.508 0.508)
			(layers "B.Cu" "B.Mask" "B.Paste")
			(net "P1V8_M2")
		)
		(zone
			(layer "B.Cu")
			(hatch none 0.5)
			(connect_pads
				(clearance 0)
			)
			(min_thickness 0.25)
			(keepout
				(tracks not_allowed)
				(vias allowed)
				(pads allowed)
				(copperpour not_allowed)
				(footprints allowed)
			)
			(placement
				(enabled no)
				(sheetname "")
			)
			(fill
				(thermal_gap 0.5)
				(thermal_bridge_width 0.5)
				(island_removal_mode 0)
			)
			(polygon
				(pts
					(xy 393.192 -19.5453) (xy 393.7 -19.5453) (xy 393.7 -19.1643) (xy 393.192 -19.1643)
				)
			)
		)
		(zone
			(layer "B.Cu")
			(hatch none 0.5)
			(connect_pads
				(clearance 0)
			)
			(min_thickness 0.25)
			(keepout
				(tracks allowed)
				(vias not_allowed)
				(pads allowed)
				(copperpour not_allowed)
				(footprints allowed)
			)
			(placement
				(enabled no)
				(sheetname "")
			)
			(fill
				(thermal_gap 0.5)
				(thermal_bridge_width 0.5)
				(island_removal_mode 0)
			)
			(polygon
				(pts
					(xy 393.192 -19.1643) (xy 393.7 -19.1643) (xy 393.7 -19.5453) (xy 393.192 -19.5453)
				)
			)
		)
	)
	(footprint ""
		(layer "B.Cu")
		(at 457.8096 -142.9004)
		(property "Reference" "R1L28"
			(at 0 0 0)
			(layer "B.SilkS")
			(hide yes)
			(effects
				(font
					(size 1.27 1.27)
				)
				(justify mirror)
			)
		)
		(property "Value" ""
			(at 0 0 0)
			(layer "B.Fab")
			(effects
				(font
					(size 1.27 1.27)
				)
				(justify mirror)
			)
		)
		(duplicate_pad_numbers_are_jumpers no)
		(fp_poly
			(pts
				(xy 0.2794 -0.1016) (xy -0.2794 -0.1016) (xy -0.2794 0.9906) (xy 0.2794 0.9906)
			)
			(stroke
				(width 0)
				(type default)
			)
			(fill no)
			(layer "B.CrtYd")
		)
		(fp_line
			(start -0.2794 -0.1016)
			(end 0.2794 -0.1016)
			(stroke
				(width 0.1)
				(type default)
			)
			(layer "B.Fab")
		)
		(fp_line
			(start -0.2794 0.9906)
			(end -0.2794 -0.1016)
			(stroke
				(width 0.1)
				(type default)
			)
			(layer "B.Fab")
		)
		(fp_line
			(start 0.2794 -0.1016)
			(end 0.2794 0.9906)
			(stroke
				(width 0.1)
				(type default)
			)
			(layer "B.Fab")
		)
		(fp_line
			(start 0.2794 0.9906)
			(end -0.2794 0.9906)
			(stroke
				(width 0.1)
				(type default)
			)
			(layer "B.Fab")
		)
		(pad "1" smd rect
			(at 0 0 180)
			(size 0.508 0.508)
			(layers "B.Cu" "B.Mask" "B.Paste")
			(net "P3V3_STBY")
		)
		(pad "2" smd rect
			(at 0 0.889 180)
			(size 0.508 0.508)
			(layers "B.Cu" "B.Mask" "B.Paste")
			(net "FM_DEBUG_RST_BTN_R1_N")
		)
		(zone
			(layer "B.Cu")
			(hatch none 0.5)
			(connect_pads
				(clearance 0)
			)
			(min_thickness 0.25)
			(keepout
				(tracks allowed)
				(vias not_allowed)
				(pads allowed)
				(copperpour not_allowed)
				(footprints allowed)
			)
			(placement
				(enabled no)
				(sheetname "")
			)
			(fill
				(thermal_gap 0.5)
				(thermal_bridge_width 0.5)
				(island_removal_mode 0)
			)
			(polygon
				(pts
					(xy 458.0636 -142.6464) (xy 457.5556 -142.6464) (xy 457.5556 -142.2654) (xy 458.0636 -142.2654)
				)
			)
		)
		(zone
			(layer "B.Cu")
			(hatch none 0.5)
			(connect_pads
				(clearance 0)
			)
			(min_thickness 0.25)
			(keepout
				(tracks not_allowed)
				(vias allowed)
				(pads allowed)
				(copperpour not_allowed)
				(footprints allowed)
			)
			(placement
				(enabled no)
				(sheetname "")
			)
			(fill
				(thermal_gap 0.5)
				(thermal_bridge_width 0.5)
				(island_removal_mode 0)
			)
			(polygon
				(pts
					(xy 458.0636 -142.2654) (xy 457.5556 -142.2654) (xy 457.5556 -142.6464) (xy 458.0636 -142.6464)
				)
			)
		)
	)
	(footprint ""
		(layer "B.Cu")
		(at 403.8854 3.3782 -90)
		(property "Reference" "R2U44"
			(at 0 0 90)
			(layer "B.SilkS")
			(hide yes)
			(effects
				(font
					(size 1.27 1.27)
				)
				(justify mirror)
			)
		)
		(property "Value" ""
			(at 0 0 90)
			(layer "B.Fab")
			(effects
				(font
					(size 1.27 1.27)
				)
				(justify mirror)
			)
		)
		(duplicate_pad_numbers_are_jumpers no)
		(fp_poly
			(pts
				(xy 0.2794 -0.1016) (xy -0.2794 -0.1016) (xy -0.2794 0.9906) (xy 0.2794 0.9906)
			)
			(stroke
				(width 0)
				(type default)
			)
			(fill no)
			(layer "B.CrtYd")
		)
		(fp_line
			(start -0.2794 0.9906)
			(end -0.2794 -0.1016)
			(stroke
				(width 0.1)
				(type default)
			)
			(layer "B.Fab")
		)
		(fp_line
			(start 0.2794 0.9906)
			(end -0.2794 0.9906)
			(stroke
				(width 0.1)
				(type default)
			)
			(layer "B.Fab")
		)
		(fp_line
			(start -0.2794 -0.1016)
			(end 0.2794 -0.1016)
			(stroke
				(width 0.1)
				(type default)
			)
			(layer "B.Fab")
		)
		(fp_line
			(start 0.2794 -0.1016)
			(end 0.2794 0.9906)
			(stroke
				(width 0.1)
				(type default)
			)
			(layer "B.Fab")
		)
		(pad "1" smd rect
			(at 0 0 90)
			(size 0.508 0.508)
			(layers "B.Cu" "B.Mask" "B.Paste")
			(net "FAN_PWM_OUT_SYS1_BUF")
		)
		(pad "2" smd rect
			(at 0 0.889 90)
			(size 0.508 0.508)
			(layers "B.Cu" "B.Mask" "B.Paste")
			(net "FAN_PWM_OUT_SYS1_R")
		)
		(zone
			(layer "B.Cu")
			(hatch none 0.5)
			(connect_pads
				(clearance 0)
			)
			(min_thickness 0.25)
			(keepout
				(tracks not_allowed)
				(vias allowed)
				(pads allowed)
				(copperpour not_allowed)
				(footprints allowed)
			)
			(placement
				(enabled no)
				(sheetname "")
			)
			(fill
				(thermal_gap 0.5)
				(thermal_bridge_width 0.5)
				(island_removal_mode 0)
			)
			(polygon
				(pts
					(xy 403.2504 3.6322) (xy 403.2504 3.1242) (xy 403.6314 3.1242) (xy 403.6314 3.6322)
				)
			)
		)
		(zone
			(layer "B.Cu")
			(hatch none 0.5)
			(connect_pads
				(clearance 0)
			)
			(min_thickness 0.25)
			(keepout
				(tracks allowed)
				(vias not_allowed)
				(pads allowed)
				(copperpour not_allowed)
				(footprints allowed)
			)
			(placement
				(enabled no)
				(sheetname "")
			)
			(fill
				(thermal_gap 0.5)
				(thermal_bridge_width 0.5)
				(island_removal_mode 0)
			)
			(polygon
				(pts
					(xy 403.6314 3.6322) (xy 403.6314 3.1242) (xy 403.2504 3.1242) (xy 403.2504 3.6322)
				)
			)
		)
	)
	(footprint ""
		(layer "B.Cu")
		(at 421.66032 -73.962514)
		(property "Reference" "C1R28"
			(at 0 0 0)
			(layer "B.SilkS")
			(hide yes)
			(effects
				(font
					(size 1.27 1.27)
				)
				(justify mirror)
			)
		)
		(property "Value" ""
			(at 0 0 0)
			(layer "B.Fab")
			(effects
				(font
					(size 1.27 1.27)
				)
				(justify mirror)
			)
		)
		(duplicate_pad_numbers_are_jumpers no)
		(fp_poly
			(pts
				(xy -0.3048 -0.1016) (xy -0.3048 0.9906) (xy 0.3048 0.9906) (xy 0.3048 -0.1016)
			)
			(stroke
				(width 0)
				(type default)
			)
			(fill no)
			(layer "B.CrtYd")
		)
		(fp_line
			(start -0.3048 -0.1016)
			(end 0.3048 -0.1016)
			(stroke
				(width 0.1)
				(type default)
			)
			(layer "B.Fab")
		)
		(fp_line
			(start -0.3048 0.9906)
			(end -0.3048 -0.1016)
			(stroke
				(width 0.1)
				(type default)
			)
			(layer "B.Fab")
		)
		(fp_line
			(start 0.3048 -0.1016)
			(end 0.3048 0.9906)
			(stroke
				(width 0.1)
				(type default)
			)
			(layer "B.Fab")
		)
		(fp_line
			(start 0.3048 0.9906)
			(end -0.3048 0.9906)
			(stroke
				(width 0.1)
				(type default)
			)
			(layer "B.Fab")
		)
		(pad "1" smd rect
			(at 0 0 180)
			(size 0.508 0.508)
			(layers "B.Cu" "B.Mask" "B.Paste")
			(net "P3V3_STBY")
		)
		(pad "2" smd rect
			(at 0 0.889 180)
			(size 0.508 0.508)
			(layers "B.Cu" "B.Mask" "B.Paste")
			(net "GND")
		)
		(zone
			(layer "B.Cu")
			(hatch none 0.5)
			(connect_pads
				(clearance 0)
			)
			(min_thickness 0.25)
			(keepout
				(tracks allowed)
				(vias not_allowed)
				(pads allowed)
				(copperpour not_allowed)
				(footprints allowed)
			)
			(placement
				(enabled no)
				(sheetname "")
			)
			(fill
				(thermal_gap 0.5)
				(thermal_bridge_width 0.5)
				(island_removal_mode 0)
			)
			(polygon
				(pts
					(xy 421.91432 -73.708514) (xy 421.40632 -73.708514) (xy 421.40632 -73.327514) (xy 421.91432 -73.327514)
				)
			)
		)
		(zone
			(layer "B.Cu")
			(hatch none 0.5)
			(connect_pads
				(clearance 0)
			)
			(min_thickness 0.25)
			(keepout
				(tracks not_allowed)
				(vias allowed)
				(pads allowed)
				(copperpour not_allowed)
				(footprints allowed)
			)
			(placement
				(enabled no)
				(sheetname "")
			)
			(fill
				(thermal_gap 0.5)
				(thermal_bridge_width 0.5)
				(island_removal_mode 0)
			)
			(polygon
				(pts
					(xy 421.91432 -73.327514) (xy 421.40632 -73.327514) (xy 421.40632 -73.708514) (xy 421.91432 -73.708514)
				)
			)
		)
	)
)
